(kicad_pcb
	(version 20241229)
	(generator "pcbnew")
	(generator_version "9.0")
	(general
		(thickness 1.599998)
		(legacy_teardrops no)
	)
	(paper "A4")
	(title_block
		(title "Artix - Datacenter Secure Control Module (DC-SCM)")
		(date "2024-11-06")
		(rev "1.1.3")
		(comment 9 "footprints 360-366 of 544")
	)
	(layers
		(0 "F.Cu" signal)
		(4 "In1.Cu" signal)
		(6 "In2.Cu" signal)
		(8 "In3.Cu" signal)
		(10 "In4.Cu" signal)
		(12 "In5.Cu" signal)
		(14 "In6.Cu" signal)
		(2 "B.Cu" signal)
		(9 "F.Adhes" user "F.Adhesive")
		(11 "B.Adhes" user "B.Adhesive")
		(13 "F.Paste" user)
		(15 "B.Paste" user)
		(5 "F.SilkS" user "F.Silkscreen")
		(7 "B.SilkS" user "B.Silkscreen")
		(1 "F.Mask" user)
		(3 "B.Mask" user)
		(17 "Dwgs.User" user "User.Drawings")
		(19 "Cmts.User" user "User.Comments")
		(21 "Eco1.User" user "User.Eco1")
		(23 "Eco2.User" user "User.Eco2")
		(25 "Edge.Cuts" user)
		(27 "Margin" user)
		(31 "F.CrtYd" user "F.Courtyard")
		(29 "B.CrtYd" user "B.Courtyard")
		(35 "F.Fab" user)
		(33 "B.Fab" user)
	)
	(footprint "antmicro-footprints:R_0402_1005Metric"
		(layer "B.Cu")
		(at 102.6 102.9 -90)
		(descr "Resistor SMD 0402")
		(tags "resistor SMD 0402")
		(property "Reference" "R127"
			(at 0.7 -0.35 90)
			(layer "B.SilkS")
			(effects
				(font
					(size 0.7 0.7)
					(thickness 0.15)
				)
				(justify left bottom mirror)
			)
		)
		(property "Value" "R_10k2_0402"
			(at 0 -1.4 90)
			(layer "B.Fab")
			(effects
				(font
					(size 0.7 0.7)
					(thickness 0.15)
				)
				(justify left bottom mirror)
			)
		)
		(property "Datasheet" "https://www.bourns.com/docs/product-datasheets/cr.pdf"
			(at 0 0 270)
			(layer "F.Fab")
			(hide yes)
			(effects
				(font
					(size 1.27 1.27)
					(thickness 0.15)
				)
			)
		)
		(property "Description" "SMD Chip Resistor"
			(at 0 0 270)
			(layer "F.Fab")
			(hide yes)
			(effects
				(font
					(size 1.27 1.27)
					(thickness 0.15)
				)
			)
		)
		(property "Author" "Antmicro"
			(at -0.3 205.5 0)
			(layer "B.Fab")
			(hide yes)
			(effects
				(font
					(size 1 1)
					(thickness 0.15)
				)
				(justify mirror)
			)
		)
		(property "License" "Apache-2.0"
			(at -0.3 205.5 0)
			(layer "B.Fab")
			(hide yes)
			(effects
				(font
					(size 1 1)
					(thickness 0.15)
				)
				(justify mirror)
			)
		)
		(property "MPN" "CR0402-FX-1022GLF"
			(at -0.3 205.5 0)
			(layer "B.Fab")
			(hide yes)
			(effects
				(font
					(size 1 1)
					(thickness 0.15)
				)
				(justify mirror)
			)
		)
		(property "Manufacturer" "Bourns"
			(at -0.3 205.5 0)
			(layer "B.Fab")
			(hide yes)
			(effects
				(font
					(size 1 1)
					(thickness 0.15)
				)
				(justify mirror)
			)
		)
		(property "Tolerance" "1%"
			(at -0.3 205.5 0)
			(layer "B.Fab")
			(hide yes)
			(effects
				(font
					(size 1 1)
					(thickness 0.15)
				)
				(justify mirror)
			)
		)
		(property "Val" "10k2"
			(at -0.3 205.5 0)
			(layer "B.Fab")
			(hide yes)
			(effects
				(font
					(size 1 1)
					(thickness 0.15)
				)
				(justify mirror)
			)
		)
		(sheetname "/Ethernet/")
		(sheetfile "ethernet.kicad_sch")
		(attr smd)
		(fp_rect
			(start -0.925 0.47)
			(end 0.925 -0.47)
			(stroke
				(width 0.05)
				(type default)
			)
			(fill no)
			(layer "B.CrtYd")
		)
		(fp_rect
			(start -0.5 0.25)
			(end 0.5 -0.25)
			(stroke
				(width 0.15)
				(type solid)
			)
			(fill no)
			(layer "B.Fab")
		)
		(pad "1" smd roundrect
			(at -0.48 0 270)
			(size 0.59 0.64)
			(layers "B.Cu" "B.Mask" "B.Paste")
			(roundrect_rratio 0.25)
			(net 407 "RGMII_RXD0")
			(pintype "passive")
		)
		(pad "2" smd roundrect
			(at 0.48 0 270)
			(size 0.59 0.64)
			(layers "B.Cu" "B.Mask" "B.Paste")
			(roundrect_rratio 0.25)
			(net 2 "VCC3V3")
			(pintype "passive")
		)
	)
	(footprint "antmicro-footprints:R_0402_1005Metric"
		(layer "B.Cu")
		(at 101.65 102.9 -90)
		(descr "Resistor SMD 0402")
		(tags "resistor SMD 0402")
		(property "Reference" "R148"
			(at 0.7 -0.35 90)
			(layer "B.SilkS")
			(effects
				(font
					(size 0.7 0.7)
					(thickness 0.15)
				)
				(justify left bottom mirror)
			)
		)
		(property "Value" "R_10k2_0402"
			(at 0 -1.4 90)
			(layer "B.Fab")
			(effects
				(font
					(size 0.7 0.7)
					(thickness 0.15)
				)
				(justify left bottom mirror)
			)
		)
		(property "Datasheet" "https://www.bourns.com/docs/product-datasheets/cr.pdf"
			(at 0 0 270)
			(layer "F.Fab")
			(hide yes)
			(effects
				(font
					(size 1.27 1.27)
					(thickness 0.15)
				)
			)
		)
		(property "Description" "SMD Chip Resistor"
			(at 0 0 270)
			(layer "F.Fab")
			(hide yes)
			(effects
				(font
					(size 1.27 1.27)
					(thickness 0.15)
				)
			)
		)
		(property "Author" "Antmicro"
			(at -1.25 204.55 0)
			(layer "B.Fab")
			(hide yes)
			(effects
				(font
					(size 1 1)
					(thickness 0.15)
				)
				(justify mirror)
			)
		)
		(property "License" "Apache-2.0"
			(at -1.25 204.55 0)
			(layer "B.Fab")
			(hide yes)
			(effects
				(font
					(size 1 1)
					(thickness 0.15)
				)
				(justify mirror)
			)
		)
		(property "MPN" "CR0402-FX-1022GLF"
			(at -1.25 204.55 0)
			(layer "B.Fab")
			(hide yes)
			(effects
				(font
					(size 1 1)
					(thickness 0.15)
				)
				(justify mirror)
			)
		)
		(property "Manufacturer" "Bourns"
			(at -1.25 204.55 0)
			(layer "B.Fab")
			(hide yes)
			(effects
				(font
					(size 1 1)
					(thickness 0.15)
				)
				(justify mirror)
			)
		)
		(property "Tolerance" "1%"
			(at -1.25 204.55 0)
			(layer "B.Fab")
			(hide yes)
			(effects
				(font
					(size 1 1)
					(thickness 0.15)
				)
				(justify mirror)
			)
		)
		(property "Val" "10k2"
			(at -1.25 204.55 0)
			(layer "B.Fab")
			(hide yes)
			(effects
				(font
					(size 1 1)
					(thickness 0.15)
				)
				(justify mirror)
			)
		)
		(sheetname "/Ethernet/")
		(sheetfile "ethernet.kicad_sch")
		(attr smd)
		(fp_rect
			(start -0.925 0.47)
			(end 0.925 -0.47)
			(stroke
				(width 0.05)
				(type default)
			)
			(fill no)
			(layer "B.CrtYd")
		)
		(fp_rect
			(start -0.5 0.25)
			(end 0.5 -0.25)
			(stroke
				(width 0.15)
				(type solid)
			)
			(fill no)
			(layer "B.Fab")
		)
		(pad "1" smd roundrect
			(at -0.48 0 270)
			(size 0.59 0.64)
			(layers "B.Cu" "B.Mask" "B.Paste")
			(roundrect_rratio 0.25)
			(net 408 "RGMII_RXD1")
			(pintype "passive")
		)
		(pad "2" smd roundrect
			(at 0.48 0 270)
			(size 0.59 0.64)
			(layers "B.Cu" "B.Mask" "B.Paste")
			(roundrect_rratio 0.25)
			(net 2 "VCC3V3")
			(pintype "passive")
		)
	)
	(footprint "antmicro-footprints:R_0402_1005Metric"
		(layer "B.Cu")
		(at 100.7 102.9 -90)
		(descr "Resistor SMD 0402")
		(tags "resistor SMD 0402")
		(property "Reference" "R149"
			(at 0.7 -0.35 90)
			(layer "B.SilkS")
			(effects
				(font
					(size 0.7 0.7)
					(thickness 0.15)
				)
				(justify left bottom mirror)
			)
		)
		(property "Value" "R_10k2_0402"
			(at 0 -1.4 90)
			(layer "B.Fab")
			(effects
				(font
					(size 0.7 0.7)
					(thickness 0.15)
				)
				(justify left bottom mirror)
			)
		)
		(property "Datasheet" "https://www.bourns.com/docs/product-datasheets/cr.pdf"
			(at 0 0 270)
			(layer "F.Fab")
			(hide yes)
			(effects
				(font
					(size 1.27 1.27)
					(thickness 0.15)
				)
			)
		)
		(property "Description" "SMD Chip Resistor"
			(at 0 0 270)
			(layer "F.Fab")
			(hide yes)
			(effects
				(font
					(size 1.27 1.27)
					(thickness 0.15)
				)
			)
		)
		(property "Author" "Antmicro"
			(at -2.2 203.6 0)
			(layer "B.Fab")
			(hide yes)
			(effects
				(font
					(size 1 1)
					(thickness 0.15)
				)
				(justify mirror)
			)
		)
		(property "License" "Apache-2.0"
			(at -2.2 203.6 0)
			(layer "B.Fab")
			(hide yes)
			(effects
				(font
					(size 1 1)
					(thickness 0.15)
				)
				(justify mirror)
			)
		)
		(property "MPN" "CR0402-FX-1022GLF"
			(at -2.2 203.6 0)
			(layer "B.Fab")
			(hide yes)
			(effects
				(font
					(size 1 1)
					(thickness 0.15)
				)
				(justify mirror)
			)
		)
		(property "Manufacturer" "Bourns"
			(at -2.2 203.6 0)
			(layer "B.Fab")
			(hide yes)
			(effects
				(font
					(size 1 1)
					(thickness 0.15)
				)
				(justify mirror)
			)
		)
		(property "Tolerance" "1%"
			(at -2.2 203.6 0)
			(layer "B.Fab")
			(hide yes)
			(effects
				(font
					(size 1 1)
					(thickness 0.15)
				)
				(justify mirror)
			)
		)
		(property "Val" "10k2"
			(at -2.2 203.6 0)
			(layer "B.Fab")
			(hide yes)
			(effects
				(font
					(size 1 1)
					(thickness 0.15)
				)
				(justify mirror)
			)
		)
		(sheetname "/Ethernet/")
		(sheetfile "ethernet.kicad_sch")
		(attr smd)
		(fp_rect
			(start -0.925 0.47)
			(end 0.925 -0.47)
			(stroke
				(width 0.05)
				(type default)
			)
			(fill no)
			(layer "B.CrtYd")
		)
		(fp_rect
			(start -0.5 0.25)
			(end 0.5 -0.25)
			(stroke
				(width 0.15)
				(type solid)
			)
			(fill no)
			(layer "B.Fab")
		)
		(pad "1" smd roundrect
			(at -0.48 0 270)
			(size 0.59 0.64)
			(layers "B.Cu" "B.Mask" "B.Paste")
			(roundrect_rratio 0.25)
			(net 409 "RGMII_RXD2")
			(pintype "passive")
		)
		(pad "2" smd roundrect
			(at 0.48 0 270)
			(size 0.59 0.64)
			(layers "B.Cu" "B.Mask" "B.Paste")
			(roundrect_rratio 0.25)
			(net 2 "VCC3V3")
			(pintype "passive")
		)
	)
	(footprint "antmicro-footprints:R_0402_1005Metric"
		(layer "B.Cu")
		(at 99.75 102.9 -90)
		(descr "Resistor SMD 0402")
		(tags "resistor SMD 0402")
		(property "Reference" "R150"
			(at 0.7 -0.35 90)
			(layer "B.SilkS")
			(effects
				(font
					(size 0.7 0.7)
					(thickness 0.15)
				)
				(justify left bottom mirror)
			)
		)
		(property "Value" "R_10k2_0402"
			(at 0 -1.4 90)
			(layer "B.Fab")
			(effects
				(font
					(size 0.7 0.7)
					(thickness 0.15)
				)
				(justify left bottom mirror)
			)
		)
		(property "Datasheet" "https://www.bourns.com/docs/product-datasheets/cr.pdf"
			(at 0 0 270)
			(layer "F.Fab")
			(hide yes)
			(effects
				(font
					(size 1.27 1.27)
					(thickness 0.15)
				)
			)
		)
		(property "Description" "SMD Chip Resistor"
			(at 0 0 270)
			(layer "F.Fab")
			(hide yes)
			(effects
				(font
					(size 1.27 1.27)
					(thickness 0.15)
				)
			)
		)
		(property "Author" "Antmicro"
			(at -3.15 202.65 0)
			(layer "B.Fab")
			(hide yes)
			(effects
				(font
					(size 1 1)
					(thickness 0.15)
				)
				(justify mirror)
			)
		)
		(property "License" "Apache-2.0"
			(at -3.15 202.65 0)
			(layer "B.Fab")
			(hide yes)
			(effects
				(font
					(size 1 1)
					(thickness 0.15)
				)
				(justify mirror)
			)
		)
		(property "MPN" "CR0402-FX-1022GLF"
			(at -3.15 202.65 0)
			(layer "B.Fab")
			(hide yes)
			(effects
				(font
					(size 1 1)
					(thickness 0.15)
				)
				(justify mirror)
			)
		)
		(property "Manufacturer" "Bourns"
			(at -3.15 202.65 0)
			(layer "B.Fab")
			(hide yes)
			(effects
				(font
					(size 1 1)
					(thickness 0.15)
				)
				(justify mirror)
			)
		)
		(property "Tolerance" "1%"
			(at -3.15 202.65 0)
			(layer "B.Fab")
			(hide yes)
			(effects
				(font
					(size 1 1)
					(thickness 0.15)
				)
				(justify mirror)
			)
		)
		(property "Val" "10k2"
			(at -3.15 202.65 0)
			(layer "B.Fab")
			(hide yes)
			(effects
				(font
					(size 1 1)
					(thickness 0.15)
				)
				(justify mirror)
			)
		)
		(sheetname "/Ethernet/")
		(sheetfile "ethernet.kicad_sch")
		(attr smd)
		(fp_rect
			(start -0.925 0.47)
			(end 0.925 -0.47)
			(stroke
				(width 0.05)
				(type default)
			)
			(fill no)
			(layer "B.CrtYd")
		)
		(fp_rect
			(start -0.5 0.25)
			(end 0.5 -0.25)
			(stroke
				(width 0.15)
				(type solid)
			)
			(fill no)
			(layer "B.Fab")
		)
		(pad "1" smd roundrect
			(at -0.48 0 270)
			(size 0.59 0.64)
			(layers "B.Cu" "B.Mask" "B.Paste")
			(roundrect_rratio 0.25)
			(net 410 "RGMII_RXD3")
			(pintype "passive")
		)
		(pad "2" smd roundrect
			(at 0.48 0 270)
			(size 0.59 0.64)
			(layers "B.Cu" "B.Mask" "B.Paste")
			(roundrect_rratio 0.25)
			(net 2 "VCC3V3")
			(pintype "passive")
		)
	)
	(footprint "antmicro-footprints:R_0402_1005Metric"
		(layer "B.Cu")
		(at 103.55 102.9 -90)
		(descr "Resistor SMD 0402")
		(tags "resistor SMD 0402")
		(property "Reference" "R151"
			(at 0.7 -0.35 90)
			(layer "B.SilkS")
			(effects
				(font
					(size 0.7 0.7)
					(thickness 0.15)
				)
				(justify left bottom mirror)
			)
		)
		(property "Value" "R_10k2_0402"
			(at 0 -1.4 90)
			(layer "B.Fab")
			(effects
				(font
					(size 0.7 0.7)
					(thickness 0.15)
				)
				(justify left bottom mirror)
			)
		)
		(property "Datasheet" "https://www.bourns.com/docs/product-datasheets/cr.pdf"
			(at 0 0 270)
			(layer "F.Fab")
			(hide yes)
			(effects
				(font
					(size 1.27 1.27)
					(thickness 0.15)
				)
			)
		)
		(property "Description" "SMD Chip Resistor"
			(at 0 0 270)
			(layer "F.Fab")
			(hide yes)
			(effects
				(font
					(size 1.27 1.27)
					(thickness 0.15)
				)
			)
		)
		(property "Author" "Antmicro"
			(at 0.65 206.45 0)
			(layer "B.Fab")
			(hide yes)
			(effects
				(font
					(size 1 1)
					(thickness 0.15)
				)
				(justify mirror)
			)
		)
		(property "License" "Apache-2.0"
			(at 0.65 206.45 0)
			(layer "B.Fab")
			(hide yes)
			(effects
				(font
					(size 1 1)
					(thickness 0.15)
				)
				(justify mirror)
			)
		)
		(property "MPN" "CR0402-FX-1022GLF"
			(at 0.65 206.45 0)
			(layer "B.Fab")
			(hide yes)
			(effects
				(font
					(size 1 1)
					(thickness 0.15)
				)
				(justify mirror)
			)
		)
		(property "Manufacturer" "Bourns"
			(at 0.65 206.45 0)
			(layer "B.Fab")
			(hide yes)
			(effects
				(font
					(size 1 1)
					(thickness 0.15)
				)
				(justify mirror)
			)
		)
		(property "Tolerance" "1%"
			(at 0.65 206.45 0)
			(layer "B.Fab")
			(hide yes)
			(effects
				(font
					(size 1 1)
					(thickness 0.15)
				)
				(justify mirror)
			)
		)
		(property "Val" "10k2"
			(at 0.65 206.45 0)
			(layer "B.Fab")
			(hide yes)
			(effects
				(font
					(size 1 1)
					(thickness 0.15)
				)
				(justify mirror)
			)
		)
		(sheetname "/Ethernet/")
		(sheetfile "ethernet.kicad_sch")
		(attr smd)
		(fp_rect
			(start -0.925 0.47)
			(end 0.925 -0.47)
			(stroke
				(width 0.05)
				(type default)
			)
			(fill no)
			(layer "B.CrtYd")
		)
		(fp_rect
			(start -0.5 0.25)
			(end 0.5 -0.25)
			(stroke
				(width 0.15)
				(type solid)
			)
			(fill no)
			(layer "B.Fab")
		)
		(pad "1" smd roundrect
			(at -0.48 0 270)
			(size 0.59 0.64)
			(layers "B.Cu" "B.Mask" "B.Paste")
			(roundrect_rratio 0.25)
			(net 411 "RGMII_RX_DV")
			(pintype "passive")
		)
		(pad "2" smd roundrect
			(at 0.48 0 270)
			(size 0.59 0.64)
			(layers "B.Cu" "B.Mask" "B.Paste")
			(roundrect_rratio 0.25)
			(net 2 "VCC3V3")
			(pintype "passive")
		)
	)
	(footprint "antmicro-footprints:R_0402_1005Metric"
		(layer "B.Cu")
		(at 104.5 102.9 -90)
		(descr "Resistor SMD 0402")
		(tags "resistor SMD 0402")
		(property "Reference" "R152"
			(at 0.7 -0.35 90)
			(layer "B.SilkS")
			(effects
				(font
					(size 0.7 0.7)
					(thickness 0.15)
				)
				(justify left bottom mirror)
			)
		)
		(property "Value" "R_10k2_0402"
			(at 0 -1.4 90)
			(layer "B.Fab")
			(effects
				(font
					(size 0.7 0.7)
					(thickness 0.15)
				)
				(justify left bottom mirror)
			)
		)
		(property "Datasheet" "https://www.bourns.com/docs/product-datasheets/cr.pdf"
			(at 0 0 270)
			(layer "F.Fab")
			(hide yes)
			(effects
				(font
					(size 1.27 1.27)
					(thickness 0.15)
				)
			)
		)
		(property "Description" "SMD Chip Resistor"
			(at 0 0 270)
			(layer "F.Fab")
			(hide yes)
			(effects
				(font
					(size 1.27 1.27)
					(thickness 0.15)
				)
			)
		)
		(property "Author" "Antmicro"
			(at 1.6 207.4 0)
			(layer "B.Fab")
			(hide yes)
			(effects
				(font
					(size 1 1)
					(thickness 0.15)
				)
				(justify mirror)
			)
		)
		(property "License" "Apache-2.0"
			(at 1.6 207.4 0)
			(layer "B.Fab")
			(hide yes)
			(effects
				(font
					(size 1 1)
					(thickness 0.15)
				)
				(justify mirror)
			)
		)
		(property "MPN" "CR0402-FX-1022GLF"
			(at 1.6 207.4 0)
			(layer "B.Fab")
			(hide yes)
			(effects
				(font
					(size 1 1)
					(thickness 0.15)
				)
				(justify mirror)
			)
		)
		(property "Manufacturer" "Bourns"
			(at 1.6 207.4 0)
			(layer "B.Fab")
			(hide yes)
			(effects
				(font
					(size 1 1)
					(thickness 0.15)
				)
				(justify mirror)
			)
		)
		(property "Tolerance" "1%"
			(at 1.6 207.4 0)
			(layer "B.Fab")
			(hide yes)
			(effects
				(font
					(size 1 1)
					(thickness 0.15)
				)
				(justify mirror)
			)
		)
		(property "Val" "10k2"
			(at 1.6 207.4 0)
			(layer "B.Fab")
			(hide yes)
			(effects
				(font
					(size 1 1)
					(thickness 0.15)
				)
				(justify mirror)
			)
		)
		(sheetname "/Ethernet/")
		(sheetfile "ethernet.kicad_sch")
		(attr smd)
		(fp_rect
			(start -0.925 0.47)
			(end 0.925 -0.47)
			(stroke
				(width 0.05)
				(type default)
			)
			(fill no)
			(layer "B.CrtYd")
		)
		(fp_rect
			(start -0.5 0.25)
			(end 0.5 -0.25)
			(stroke
				(width 0.15)
				(type solid)
			)
			(fill no)
			(layer "B.Fab")
		)
		(pad "1" smd roundrect
			(at -0.48 0 270)
			(size 0.59 0.64)
			(layers "B.Cu" "B.Mask" "B.Paste")
			(roundrect_rratio 0.25)
			(net 412 "RGMII_RX_CLK")
			(pintype "passive")
		)
		(pad "2" smd roundrect
			(at 0.48 0 270)
			(size 0.59 0.64)
			(layers "B.Cu" "B.Mask" "B.Paste")
			(roundrect_rratio 0.25)
			(net 2 "VCC3V3")
			(pintype "passive")
		)
	)
	(footprint "antmicro-footprints:R_0402_1005Metric"
		(layer "B.Cu")
		(at 107.35 102.9 -90)
		(descr "Resistor SMD 0402")
		(tags "resistor SMD 0402")
		(property "Reference" "R153"
			(at 0.7 -0.35 90)
			(layer "B.SilkS")
			(effects
				(font
					(size 0.7 0.7)
					(thickness 0.15)
				)
				(justify left bottom mirror)
			)
		)
		(property "Value" "R_10k2_0402"
			(at 0 -1.4 90)
			(layer "B.Fab")
			(effects
				(font
					(size 0.7 0.7)
					(thickness 0.15)
				)
				(justify left bottom mirror)
			)
		)
		(property "Datasheet" "https://www.bourns.com/docs/product-datasheets/cr.pdf"
			(at 0 0 270)
			(layer "F.Fab")
			(hide yes)
			(effects
				(font
					(size 1.27 1.27)
					(thickness 0.15)
				)
			)
		)
		(property "Description" "SMD Chip Resistor"
			(at 0 0 270)
			(layer "F.Fab")
			(hide yes)
			(effects
				(font
					(size 1.27 1.27)
					(thickness 0.15)
				)
			)
		)
		(property "Author" "Antmicro"
			(at 4.45 210.25 0)
			(layer "B.Fab")
			(hide yes)
			(effects
				(font
					(size 1 1)
					(thickness 0.15)
				)
				(justify mirror)
			)
		)
		(property "License" "Apache-2.0"
			(at 4.45 210.25 0)
			(layer "B.Fab")
			(hide yes)
			(effects
				(font
					(size 1 1)
					(thickness 0.15)
				)
				(justify mirror)
			)
		)
		(property "MPN" "CR0402-FX-1022GLF"
			(at 4.45 210.25 0)
			(layer "B.Fab")
			(hide yes)
			(effects
				(font
					(size 1 1)
					(thickness 0.15)
				)
				(justify mirror)
			)
		)
		(property "Manufacturer" "Bourns"
			(at 4.45 210.25 0)
			(layer "B.Fab")
			(hide yes)
			(effects
				(font
					(size 1 1)
					(thickness 0.15)
				)
				(justify mirror)
			)
		)
		(property "Tolerance" "1%"
			(at 4.45 210.25 0)
			(layer "B.Fab")
			(hide yes)
			(effects
				(font
					(size 1 1)
					(thickness 0.15)
				)
				(justify mirror)
			)
		)
		(property "Val" "10k2"
			(at 4.45 210.25 0)
			(layer "B.Fab")
			(hide yes)
			(effects
				(font
					(size 1 1)
					(thickness 0.15)
				)
				(justify mirror)
			)
		)
		(sheetname "/Ethernet/")
		(sheetfile "ethernet.kicad_sch")
		(attr smd)
		(fp_rect
			(start -0.925 0.47)
			(end 0.925 -0.47)
			(stroke
				(width 0.05)
				(type default)
			)
			(fill no)
			(layer "B.CrtYd")
		)
		(fp_rect
			(start -0.5 0.25)
			(end 0.5 -0.25)
			(stroke
				(width 0.15)
				(type solid)
			)
			(fill no)
			(layer "B.Fab")
		)
		(pad "1" smd roundrect
			(at -0.48 0 270)
			(size 0.59 0.64)
			(layers "B.Cu" "B.Mask" "B.Paste")
			(roundrect_rratio 0.25)
			(net 413 "RGMII_REF_CLK")
			(pintype "passive")
		)
		(pad "2" smd roundrect
			(at 0.48 0 270)
			(size 0.59 0.64)
			(layers "B.Cu" "B.Mask" "B.Paste")
			(roundrect_rratio 0.25)
			(net 2 "VCC3V3")
			(pintype "passive")
		)
	)
)
